(kicad_pcb
	(version 20241229)
	(generator "pcbnew")
	(generator_version "9.0")
	(general
		(thickness 1.6642)
		(legacy_teardrops no)
	)
	(paper "A3")
	(title_block
		(title "PolarFire SoM")
		(date "2025-07-22")
		(rev "1.1.4")
		(company "Antmicro Ltd")
		(comment 1 "www.antmicro.com")
		(comment 9 "footprints 310-313 of 470")
	)
	(layers
		(0 "F.Cu" mixed)
		(4 "In1.Cu" power)
		(6 "In2.Cu" signal)
		(8 "In3.Cu" power)
		(10 "In4.Cu" signal)
		(12 "In5.Cu" power)
		(14 "In6.Cu" power)
		(16 "In7.Cu" signal)
		(18 "In8.Cu" power)
		(20 "In9.Cu" signal)
		(22 "In10.Cu" power)
		(24 "In11.Cu" signal)
		(26 "In12.Cu" signal)
		(2 "B.Cu" mixed)
		(9 "F.Adhes" user "F.Adhesive")
		(11 "B.Adhes" user "B.Adhesive")
		(13 "F.Paste" user)
		(15 "B.Paste" user)
		(5 "F.SilkS" user "F.Silkscreen")
		(7 "B.SilkS" user "B.Silkscreen")
		(1 "F.Mask" user)
		(3 "B.Mask" user)
		(17 "Dwgs.User" user "User.Drawings")
		(19 "Cmts.User" user "User.Comments")
		(21 "Eco1.User" user "User.Eco1")
		(23 "Eco2.User" user "User.Eco2")
		(25 "Edge.Cuts" user)
		(27 "Margin" user)
		(31 "F.CrtYd" user "F.Courtyard")
		(29 "B.CrtYd" user "B.Courtyard")
		(35 "F.Fab" user)
		(33 "B.Fab" user)
	)
	(footprint "antmicro-footprints:C_0402_1005Metric"
		(layer "B.Cu")
		(at 208.1 147.44 180)
		(descr "Capacitor SMD 0402")
		(tags "capacitor SMD 0402")
		(property "Reference" "C207"
			(at 4.9 18.375 0)
			(layer "B.SilkS")
			(effects
				(font
					(size 0.7 0.7)
					(thickness 0.15)
				)
				(justify left bottom mirror)
			)
		)
		(property "Value" "C_10u_0402"
			(at -1.022927 -2.155213 0)
			(layer "B.Fab")
			(hide yes)
			(effects
				(font
					(size 0.7 0.7)
					(thickness 0.15)
				)
				(justify left bottom mirror)
			)
		)
		(property "Datasheet" "https://www.yageo.com/en/Chart/Download/pdf/CC0402MRX5R5BB106"
			(at 0 0 180)
			(layer "F.Fab")
			(hide yes)
			(effects
				(font
					(size 1.27 1.27)
					(thickness 0.15)
				)
			)
		)
		(property "Description" "SMD Multilayer Ceramic Capacitor, 10 µF, 6.3 V, 0402 [1005 Metric], ± 20%, X5R, CC Series"
			(at 0 0 180)
			(layer "F.Fab")
			(hide yes)
			(effects
				(font
					(size 1.27 1.27)
					(thickness 0.15)
				)
			)
		)
		(property "Author" "Antmicro"
			(at 416.2 294.88 0)
			(layer "B.Fab")
			(hide yes)
			(effects
				(font
					(size 1 1)
					(thickness 0.15)
				)
				(justify mirror)
			)
		)
		(property "Dielectric" ""
			(at 416.2 294.88 0)
			(layer "B.Fab")
			(hide yes)
			(effects
				(font
					(size 1 1)
					(thickness 0.15)
				)
				(justify mirror)
			)
		)
		(property "License" "Apache-2.0"
			(at 416.2 294.88 0)
			(layer "B.Fab")
			(hide yes)
			(effects
				(font
					(size 1 1)
					(thickness 0.15)
				)
				(justify mirror)
			)
		)
		(property "MPN" "CC0402MRX5R5BB106"
			(at 416.2 294.88 0)
			(layer "B.Fab")
			(hide yes)
			(effects
				(font
					(size 1 1)
					(thickness 0.15)
				)
				(justify mirror)
			)
		)
		(property "Manufacturer" "YAGEO"
			(at 416.2 294.88 0)
			(layer "B.Fab")
			(hide yes)
			(effects
				(font
					(size 1 1)
					(thickness 0.15)
				)
				(justify mirror)
			)
		)
		(property "Public" ""
			(at 416.2 294.88 0)
			(layer "B.Fab")
			(hide yes)
			(effects
				(font
					(size 1 1)
					(thickness 0.15)
				)
				(justify mirror)
			)
		)
		(property "Val" "10u"
			(at 416.2 294.88 0)
			(layer "B.Fab")
			(hide yes)
			(effects
				(font
					(size 1 1)
					(thickness 0.15)
				)
				(justify mirror)
			)
		)
		(property "Voltage" ""
			(at 416.2 294.88 0)
			(layer "B.Fab")
			(hide yes)
			(effects
				(font
					(size 1 1)
					(thickness 0.15)
				)
				(justify mirror)
			)
		)
		(sheetname "/MIPI CrossLink/")
		(sheetfile "crosslink.kicad_sch")
		(attr smd)
		(fp_rect
			(start -0.925 0.47)
			(end 0.925 -0.47)
			(stroke
				(width 0.05)
				(type default)
			)
			(fill no)
			(layer "B.CrtYd")
		)
		(fp_line
			(start 0.504 0.25)
			(end 0.504 -0.248)
			(stroke
				(width 0.15)
				(type solid)
			)
			(layer "B.Fab")
		)
		(fp_line
			(start 0.504 -0.248)
			(end -0.494 -0.248)
			(stroke
				(width 0.15)
				(type solid)
			)
			(layer "B.Fab")
		)
		(fp_line
			(start -0.494 0.25)
			(end 0.504 0.25)
			(stroke
				(width 0.15)
				(type solid)
			)
			(layer "B.Fab")
		)
		(fp_line
			(start -0.494 -0.248)
			(end -0.494 0.25)
			(stroke
				(width 0.15)
				(type solid)
			)
			(layer "B.Fab")
		)
		(fp_text user "${REFERENCE}"
			(at -0.939 -4.599 0)
			(layer "B.Fab")
			(effects
				(font
					(size 0.7 0.7)
					(thickness 0.15)
				)
				(justify left bottom mirror)
			)
		)
		(fp_text user "License: Apache-2.0"
			(at -0.939 -5.799 0)
			(layer "B.Fab")
			(effects
				(font
					(size 0.7 0.7)
					(thickness 0.15)
				)
				(justify left bottom mirror)
			)
		)
		(fp_text user "Author: Antmicro"
			(at -0.939 -3.399 0)
			(layer "B.Fab")
			(effects
				(font
					(size 0.7 0.7)
					(thickness 0.15)
				)
				(justify left bottom mirror)
			)
		)
		(pad "1" smd roundrect
			(at -0.48 0 180)
			(size 0.59 0.64)
			(layers "B.Cu" "B.Mask" "B.Paste")
			(roundrect_rratio 0.25)
			(net 417 "GND")
			(pintype "passive")
		)
		(pad "2" smd roundrect
			(at 0.48 0 180)
			(size 0.59 0.64)
			(layers "B.Cu" "B.Mask" "B.Paste")
			(roundrect_rratio 0.25)
			(net 176 "/MIPI CrossLink/CL_VCC")
			(pintype "passive")
		)
	)
	(footprint "antmicro-footprints:C_0603_1608Metric"
		(layer "B.Cu")
		(at 189.28 146.14 180)
		(descr "Capacitor SMD 0603")
		(tags "capacitor 0603")
		(property "Reference" "C47"
			(at -2.45 -3.525 0)
			(layer "B.SilkS")
			(effects
				(font
					(size 0.7 0.7)
					(thickness 0.15)
				)
				(justify left bottom mirror)
			)
		)
		(property "Value" "C_47u_0603"
			(at -1.42757 -1.770288 0)
			(layer "B.Fab")
			(hide yes)
			(effects
				(font
					(size 0.7 0.7)
					(thickness 0.15)
				)
				(justify left bottom mirror)
			)
		)
		(property "Datasheet" "https://www.murata.com/products/productdetail?partno=GRM188R60J476ME15%23"
			(at 0 0 180)
			(layer "F.Fab")
			(hide yes)
			(effects
				(font
					(size 1.27 1.27)
					(thickness 0.15)
				)
			)
		)
		(property "Description" "SMD Multilayer Ceramic Capacitor, 47 µF, 6.3 V, 0603 [1608 Metric], ± 20%, X5R, GRM Series"
			(at 0 0 180)
			(layer "F.Fab")
			(hide yes)
			(effects
				(font
					(size 1.27 1.27)
					(thickness 0.15)
				)
			)
		)
		(property "Author" "Antmicro"
			(at 378.56 292.28 0)
			(layer "B.Fab")
			(hide yes)
			(effects
				(font
					(size 1 1)
					(thickness 0.15)
				)
				(justify mirror)
			)
		)
		(property "Capacitance" "47u"
			(at 378.56 292.28 0)
			(layer "B.Fab")
			(hide yes)
			(effects
				(font
					(size 1 1)
					(thickness 0.15)
				)
				(justify mirror)
			)
		)
		(property "Dielectric" "X7R"
			(at 378.56 292.28 0)
			(layer "B.Fab")
			(hide yes)
			(effects
				(font
					(size 1 1)
					(thickness 0.15)
				)
				(justify mirror)
			)
		)
		(property "License" "Apache-2.0"
			(at 378.56 292.28 0)
			(layer "B.Fab")
			(hide yes)
			(effects
				(font
					(size 1 1)
					(thickness 0.15)
				)
				(justify mirror)
			)
		)
		(property "MPN" "GRM188R60J476ME15D"
			(at 378.56 292.28 0)
			(layer "B.Fab")
			(hide yes)
			(effects
				(font
					(size 1 1)
					(thickness 0.15)
				)
				(justify mirror)
			)
		)
		(property "Manufacturer" "Murata"
			(at 378.56 292.28 0)
			(layer "B.Fab")
			(hide yes)
			(effects
				(font
					(size 1 1)
					(thickness 0.15)
				)
				(justify mirror)
			)
		)
		(property "Public" ""
			(at 378.56 292.28 0)
			(layer "B.Fab")
			(hide yes)
			(effects
				(font
					(size 1 1)
					(thickness 0.15)
				)
				(justify mirror)
			)
		)
		(property "Val" "47u"
			(at 378.56 292.28 0)
			(layer "B.Fab")
			(hide yes)
			(effects
				(font
					(size 1 1)
					(thickness 0.15)
				)
				(justify mirror)
			)
		)
		(property "Voltage" "50V"
			(at 378.56 292.28 0)
			(layer "B.Fab")
			(hide yes)
			(effects
				(font
					(size 1 1)
					(thickness 0.15)
				)
				(justify mirror)
			)
		)
		(sheetname "/FPGA Supply/")
		(sheetfile "fpga-supply.kicad_sch")
		(attr smd)
		(fp_line
			(start -0.15 0.4)
			(end 0.15 0.4)
			(stroke
				(width 0.15)
				(type solid)
			)
			(layer "B.SilkS")
		)
		(fp_line
			(start -0.15 -0.4)
			(end 0.15 -0.4)
			(stroke
				(width 0.15)
				(type solid)
			)
			(layer "B.SilkS")
		)
		(fp_rect
			(start -1.25 0.65)
			(end 1.25 -0.65)
			(stroke
				(width 0.05)
				(type solid)
			)
			(fill no)
			(layer "B.CrtYd")
		)
		(fp_rect
			(start -0.8 0.4)
			(end 0.8 -0.4)
			(stroke
				(width 0.15)
				(type solid)
			)
			(fill no)
			(layer "B.Fab")
		)
		(fp_text user "${REFERENCE}"
			(at -1.682 -3.895 0)
			(layer "B.Fab")
			(effects
				(font
					(size 0.7 0.7)
					(thickness 0.15)
				)
				(justify left bottom mirror)
			)
		)
		(fp_text user "License: Apache-2.0"
			(at -1.682 -5.895 0)
			(layer "B.Fab")
			(effects
				(font
					(size 0.7 0.7)
					(thickness 0.15)
				)
				(justify left bottom mirror)
			)
		)
		(fp_text user "Author: Antmicro"
			(at -1.682 -4.894 0)
			(layer "B.Fab")
			(effects
				(font
					(size 0.7 0.7)
					(thickness 0.15)
				)
				(justify left bottom mirror)
			)
		)
		(pad "1" smd roundrect
			(at -0.7 0 180)
			(size 0.8 1)
			(layers "B.Cu" "B.Mask" "B.Paste")
			(roundrect_rratio 0.2)
			(net 417 "GND")
			(pintype "passive")
		)
		(pad "2" smd roundrect
			(at 0.7 0 180)
			(size 0.8 1)
			(layers "B.Cu" "B.Mask" "B.Paste")
			(roundrect_rratio 0.2)
			(net 47 "+1V05")
			(pintype "passive")
		)
	)
	(footprint "antmicro-footprints:C_0402_1005Metric"
		(layer "B.Cu")
		(at 197.04 134.73 90)
		(descr "Capacitor SMD 0402")
		(tags "capacitor SMD 0402")
		(property "Reference" "C44"
			(at 7.58 -9.615 270)
			(layer "B.SilkS")
			(effects
				(font
					(size 0.7 0.7)
					(thickness 0.15)
				)
				(justify left bottom mirror)
			)
		)
		(property "Value" "C_22n_0402"
			(at -1.022927 -2.155213 270)
			(layer "B.Fab")
			(hide yes)
			(effects
				(font
					(size 0.7 0.7)
					(thickness 0.15)
				)
				(justify left bottom mirror)
			)
		)
		(property "Datasheet" "https://www.murata.com/products/productdetail?partno=GCM155R71H223MA55%23"
			(at 0 0 90)
			(layer "F.Fab")
			(hide yes)
			(effects
				(font
					(size 1.27 1.27)
					(thickness 0.15)
				)
			)
		)
		(property "Description" "SMD Multilayer Ceramic Capacitors, 0.022 µF, 50 V, 20%, 0402 [1005 Metric], X7R"
			(at 0 0 90)
			(layer "F.Fab")
			(hide yes)
			(effects
				(font
					(size 1.27 1.27)
					(thickness 0.15)
				)
			)
		)
		(property "Author" "Antmicro"
			(at 331.77 -62.31 0)
			(layer "B.Fab")
			(hide yes)
			(effects
				(font
					(size 1 1)
					(thickness 0.15)
				)
				(justify mirror)
			)
		)
		(property "Dielectric" ""
			(at 331.77 -62.31 0)
			(layer "B.Fab")
			(hide yes)
			(effects
				(font
					(size 1 1)
					(thickness 0.15)
				)
				(justify mirror)
			)
		)
		(property "License" "Apache-2.0"
			(at 331.77 -62.31 0)
			(layer "B.Fab")
			(hide yes)
			(effects
				(font
					(size 1 1)
					(thickness 0.15)
				)
				(justify mirror)
			)
		)
		(property "MPN" "GCM155R71H223MA55D"
			(at 331.77 -62.31 0)
			(layer "B.Fab")
			(hide yes)
			(effects
				(font
					(size 1 1)
					(thickness 0.15)
				)
				(justify mirror)
			)
		)
		(property "Manufacturer" "Murata"
			(at 331.77 -62.31 0)
			(layer "B.Fab")
			(hide yes)
			(effects
				(font
					(size 1 1)
					(thickness 0.15)
				)
				(justify mirror)
			)
		)
		(property "Public" ""
			(at 331.77 -62.31 0)
			(layer "B.Fab")
			(hide yes)
			(effects
				(font
					(size 1 1)
					(thickness 0.15)
				)
				(justify mirror)
			)
		)
		(property "Val" "22n"
			(at 331.77 -62.31 0)
			(layer "B.Fab")
			(hide yes)
			(effects
				(font
					(size 1 1)
					(thickness 0.15)
				)
				(justify mirror)
			)
		)
		(property "Voltage" ""
			(at 331.77 -62.31 0)
			(layer "B.Fab")
			(hide yes)
			(effects
				(font
					(size 1 1)
					(thickness 0.15)
				)
				(justify mirror)
			)
		)
		(sheetname "/FPGA Supply/")
		(sheetfile "fpga-supply.kicad_sch")
		(attr smd)
		(fp_rect
			(start -0.925 0.47)
			(end 0.925 -0.47)
			(stroke
				(width 0.05)
				(type default)
			)
			(fill no)
			(layer "B.CrtYd")
		)
		(fp_line
			(start 0.504 -0.248)
			(end -0.494 -0.248)
			(stroke
				(width 0.15)
				(type solid)
			)
			(layer "B.Fab")
		)
		(fp_line
			(start -0.494 -0.248)
			(end -0.494 0.25)
			(stroke
				(width 0.15)
				(type solid)
			)
			(layer "B.Fab")
		)
		(fp_line
			(start 0.504 0.25)
			(end 0.504 -0.248)
			(stroke
				(width 0.15)
				(type solid)
			)
			(layer "B.Fab")
		)
		(fp_line
			(start -0.494 0.25)
			(end 0.504 0.25)
			(stroke
				(width 0.15)
				(type solid)
			)
			(layer "B.Fab")
		)
		(fp_text user "License: Apache-2.0"
			(at -0.939 -5.799 270)
			(layer "B.Fab")
			(effects
				(font
					(size 0.7 0.7)
					(thickness 0.15)
				)
				(justify left bottom mirror)
			)
		)
		(fp_text user "${REFERENCE}"
			(at -0.939 -4.599 270)
			(layer "B.Fab")
			(effects
				(font
					(size 0.7 0.7)
					(thickness 0.15)
				)
				(justify left bottom mirror)
			)
		)
		(fp_text user "Author: Antmicro"
			(at -0.939 -3.399 270)
			(layer "B.Fab")
			(effects
				(font
					(size 0.7 0.7)
					(thickness 0.15)
				)
				(justify left bottom mirror)
			)
		)
		(pad "1" smd roundrect
			(at -0.48 0 90)
			(size 0.59 0.64)
			(layers "B.Cu" "B.Mask" "B.Paste")
			(roundrect_rratio 0.25)
			(net 417 "GND")
			(pintype "passive")
		)
		(pad "2" smd roundrect
			(at 0.48 0 90)
			(size 0.59 0.64)
			(layers "B.Cu" "B.Mask" "B.Paste")
			(roundrect_rratio 0.25)
			(net 47 "+1V05")
			(pintype "passive")
		)
	)
	(footprint "antmicro-footprints:C_0402_1005Metric"
		(layer "B.Cu")
		(at 199.55 140.564 90)
		(descr "Capacitor SMD 0402")
		(tags "capacitor SMD 0402")
		(property "Reference" "C39"
			(at -1.776 3.37 90)
			(layer "B.SilkS")
			(effects
				(font
					(size 0.7 0.7)
					(thickness 0.15)
				)
				(justify right bottom mirror)
			)
		)
		(property "Value" "C_100n_0402"
			(at -1.022927 -2.155213 90)
			(layer "B.Fab")
			(hide yes)
			(effects
				(font
					(size 0.7 0.7)
					(thickness 0.15)
				)
				(justify right bottom mirror)
			)
		)
		(property "Datasheet" "https://www.murata.com/products/productdetail?partno=GRM155R61H104KE14%23"
			(at 0 0 90)
			(layer "F.Fab")
			(hide yes)
			(effects
				(font
					(size 1.27 1.27)
					(thickness 0.15)
				)
			)
		)
		(property "Description" "SMD Multilayer Ceramic Capacitor, 0.1 µF, 50 V, 0402 [1005 Metric], ± 10%, X5R, GRM Series"
			(at 0 0 90)
			(layer "F.Fab")
			(hide yes)
			(effects
				(font
					(size 1.27 1.27)
					(thickness 0.15)
				)
			)
		)
		(property "Author" "Antmicro"
			(at 340.114 -58.986 0)
			(layer "B.Fab")
			(hide yes)
			(effects
				(font
					(size 1 1)
					(thickness 0.15)
				)
				(justify mirror)
			)
		)
		(property "Dielectric" "X5R"
			(at 340.114 -58.986 0)
			(layer "B.Fab")
			(hide yes)
			(effects
				(font
					(size 1 1)
					(thickness 0.15)
				)
				(justify mirror)
			)
		)
		(property "License" "Apache-2.0"
			(at 340.114 -58.986 0)
			(layer "B.Fab")
			(hide yes)
			(effects
				(font
					(size 1 1)
					(thickness 0.15)
				)
				(justify mirror)
			)
		)
		(property "MPN" "GRM155R61H104KE14D"
			(at 340.114 -58.986 0)
			(layer "B.Fab")
			(hide yes)
			(effects
				(font
					(size 1 1)
					(thickness 0.15)
				)
				(justify mirror)
			)
		)
		(property "Manufacturer" "Murata"
			(at 340.114 -58.986 0)
			(layer "B.Fab")
			(hide yes)
			(effects
				(font
					(size 1 1)
					(thickness 0.15)
				)
				(justify mirror)
			)
		)
		(property "Public" ""
			(at 340.114 -58.986 0)
			(layer "B.Fab")
			(hide yes)
			(effects
				(font
					(size 1 1)
					(thickness 0.15)
				)
				(justify mirror)
			)
		)
		(property "Val" "100n"
			(at 340.114 -58.986 0)
			(layer "B.Fab")
			(hide yes)
			(effects
				(font
					(size 1 1)
					(thickness 0.15)
				)
				(justify mirror)
			)
		)
		(property "Voltage" "50V"
			(at 340.114 -58.986 0)
			(layer "B.Fab")
			(hide yes)
			(effects
				(font
					(size 1 1)
					(thickness 0.15)
				)
				(justify mirror)
			)
		)
		(sheetname "/FPGA Supply/")
		(sheetfile "fpga-supply.kicad_sch")
		(attr smd)
		(fp_rect
			(start -0.925 0.47)
			(end 0.925 -0.47)
			(stroke
				(width 0.05)
				(type default)
			)
			(fill no)
			(layer "B.CrtYd")
		)
		(fp_line
			(start 0.504 -0.248)
			(end -0.494 -0.248)
			(stroke
				(width 0.15)
				(type solid)
			)
			(layer "B.Fab")
		)
		(fp_line
			(start -0.494 -0.248)
			(end -0.494 0.25)
			(stroke
				(width 0.15)
				(type solid)
			)
			(layer "B.Fab")
		)
		(fp_line
			(start 0.504 0.25)
			(end 0.504 -0.248)
			(stroke
				(width 0.15)
				(type solid)
			)
			(layer "B.Fab")
		)
		(fp_line
			(start -0.494 0.25)
			(end 0.504 0.25)
			(stroke
				(width 0.15)
				(type solid)
			)
			(layer "B.Fab")
		)
		(fp_text user "Author: Antmicro"
			(at -0.939 -3.399 270)
			(layer "B.Fab")
			(effects
				(font
					(size 0.7 0.7)
					(thickness 0.15)
				)
				(justify left bottom mirror)
			)
		)
		(fp_text user "${REFERENCE}"
			(at -0.939 -4.599 270)
			(layer "B.Fab")
			(effects
				(font
					(size 0.7 0.7)
					(thickness 0.15)
				)
				(justify left bottom mirror)
			)
		)
		(fp_text user "License: Apache-2.0"
			(at -0.939 -5.799 270)
			(layer "B.Fab")
			(effects
				(font
					(size 0.7 0.7)
					(thickness 0.15)
				)
				(justify left bottom mirror)
			)
		)
		(pad "1" smd roundrect
			(at -0.48 0 90)
			(size 0.59 0.64)
			(layers "B.Cu" "B.Mask" "B.Paste")
			(roundrect_rratio 0.25)
			(net 417 "GND")
			(pintype "passive")
		)
		(pad "2" smd roundrect
			(at 0.48 0 90)
			(size 0.59 0.64)
			(layers "B.Cu" "B.Mask" "B.Paste")
			(roundrect_rratio 0.25)
			(net 47 "+1V05")
			(pintype "passive")
		)
	)
)
